#ISCELL
  pure_quanta quanta_title_block_c *
  *
#ISCELL
  standard offpage *
  page134_i116
#ISCELL
  standard offpage *
  page134_i117
#ISCELL
  standard offpage *
  page134_i124
#ISCELL
  standard offpage *
  page134_i125
#CELL
  pure_quanta q_res *
  page134_i126
#CELL
  pure_quanta q_res *
  page134_i127
#CELL
  pure_quanta q_res *
  page134_i128
#CELL
  pure_quanta 74cbtlv3126pw *
  page134_i129
#ISCELL
  logical_power universal_power *
  page134_i134
#CELL
  pure_quanta q_cap *
  page134_i135
#ISCELL
  logical_power universal_gnd *
  page134_i136
#ISCELL
  standard offpage *
  page134_i140
#ISCELL
  standard offpage *
  page134_i141
#ISCELL
  standard offpage *
  page134_i142
#ISCELL
  standard offpage *
  page134_i143
#ISCELL
  standard offpage *
  page134_i145
#CELL
  pure_quanta q_res *
  page134_i147
#CELL
  pure_quanta q_res *
  page134_i148
#ISCELL
  standard offpage *
  page134_i153
#ISCELL
  standard offpage *
  page134_i154
#ISCELL
  standard offpage *
  page134_i156
#ISCELL
  standard offpage *
  page134_i157
#ISCELL
  standard offpage *
  page134_i158
#ISCELL
  standard offpage *
  page134_i159
#ISCELL
  standard offpage *
  page134_i160
#ISCELL
  standard offpage *
  page134_i161
#ISCELL
  standard offpage *
  page134_i162
#ISCELL
  standard offpage *
  page134_i163
#ISCELL
  logical_power universal_gnd *
  page134_i164
#ISCELL
  logical_power universal_gnd *
  page134_i165
#CELL
  pure_quanta q_res *
  page134_i166
#ISCELL
  logical_power universal_power *
  page134_i167
#CELL
  pure_quanta q_res *
  page134_i168
#CELL
  pure_quanta q_res *
  page134_i169
#ISCELL
  logical_power universal_power *
  page134_i172
#CELL
  pure_quanta q_res *
  page134_i174
#CELL
  pure_quanta q_res *
  page134_i175
#CELL
  pure_quanta q_res *
  page134_i176
#CELL
  pure_quanta q_res *
  page134_i177
#CELL
  pure_quanta q_res *
  page134_i178
#CELL
  pure_quanta q_res *
  page134_i179
#CELL
  pure_quanta q_res *
  page134_i180
#ISCELL
  logical_power universal_power *
  page134_i181
#CELL
  pure_quanta 74cbtlv3126pw *
  page134_i80
#ISCELL
  logical_power universal_power *
  page134_i81
#ISCELL
  standard offpage *
  page134_i82
#ISCELL
  standard offpage *
  page134_i86
#ISCELL
  standard offpage *
  page134_i87
#ISCELL
  standard offpage *
  page134_i88
#ISCELL
  standard offpage *
  page134_i89
#CELL
  pure_quanta q_res *
  page134_i90
#ISCELL
  logical_power universal_gnd *
  page134_i91
#ISCELL
  logical_power universal_gnd *
  page134_i92
#CELL
  pure_quanta q_cap *
  page134_i93
#ISCELL
  standard offpage *
  page134_i95
#ISCELL
  standard offpage *
  page134_i97
